(kicad_pcb
	(version 20260206)
	(generator "pcbnew")
	(generator_version "10.0")
	(general
		(thickness 1.6)
		(legacy_teardrops no)
	)
	(paper "A4")
	(title_block
		(title "peb — Lightning_PEB_BRD.brd")
		(comment 1 "Lightning (Wiwynn / Facebook NVMe JBOF) / footprints 618-624 of 2563")
	)
	(layers
		(0 "F.Cu" signal "TOP")
		(4 "In1.Cu" signal "L2GND")
		(6 "In2.Cu" signal "L3")
		(8 "In3.Cu" signal "L4VCC")
		(10 "In4.Cu" signal "L5VCC")
		(12 "In5.Cu" signal "L6")
		(14 "In6.Cu" signal "L7GND")
		(2 "B.Cu" signal "BOTTOM")
		(9 "F.Adhes" user "F.Adhesive")
		(11 "B.Adhes" user "B.Adhesive")
		(13 "F.Paste" user "Package Geometry/Pastemask Top")
		(15 "B.Paste" user "Package Geometry/Pastemask Bottom")
		(5 "F.SilkS" user "Ref Des/Silkscreen Top")
		(7 "B.SilkS" user "Ref Des/Silkscreen Bottom")
		(1 "F.Mask" user "Board Geometry/Soldermask Top")
		(3 "B.Mask" user "Board Geometry/Soldermask Bottom")
		(17 "Dwgs.User" user "User.Drawings")
		(19 "Cmts.User" user "User.Comments")
		(21 "Eco1.User" user "User.Eco1")
		(23 "Eco2.User" user "User.Eco2")
		(25 "Edge.Cuts" user "Board Geometry/Outline")
		(27 "Margin" user)
		(31 "F.CrtYd" user "Package Geometry/Place Bound Top")
		(29 "B.CrtYd" user "Package Geometry/Place Bound Bottom")
		(35 "F.Fab" user "Ref Des/Assembly Top")
		(33 "B.Fab" user "Ref Des/Assembly Bottom")
	)
	(footprint ""
		(layer "F.Cu")
		(at 330.591922 -39.64559 180)
		(property "Reference" "Q30"
			(at 0 0 180)
			(layer "F.SilkS")
			(hide yes)
			(effects
				(font
					(size 1.27 1.27)
				)
			)
		)
		(property "Value" "2N7002K-1-GP"
			(at 0.127 -8.9662 180)
			(unlocked yes)
			(layer "F.Fab")
			(hide yes)
			(effects
				(font
					(size 1.016 1.016)
					(thickness 0.1524)
				)
			)
		)
		(property "Device Type" "SOT23DGS2D4H44"
			(at 0.127 -10.4902 180)
			(unlocked yes)
			(layer "F.Fab")
			(hide yes)
			(effects
				(font
					(size 1.016 1.016)
					(thickness 0.1524)
				)
			)
		)
		(duplicate_pad_numbers_are_jumpers no)
		(fp_line
			(start 1.651 1.778)
			(end 1.651 -1.778)
			(stroke
				(width 0.1524)
				(type default)
			)
			(layer "F.SilkS")
		)
		(fp_line
			(start 1.651 -1.778)
			(end -1.651 -1.778)
			(stroke
				(width 0.1524)
				(type default)
			)
			(layer "F.SilkS")
		)
		(fp_line
			(start -1.651 1.778)
			(end 1.651 1.778)
			(stroke
				(width 0.1524)
				(type default)
			)
			(layer "F.SilkS")
		)
		(fp_line
			(start -1.651 -1.778)
			(end -1.651 1.778)
			(stroke
				(width 0.1524)
				(type default)
			)
			(layer "F.SilkS")
		)
		(fp_poly
			(pts
				(xy -1.778 1.8796) (xy -1.778 -1.8796) (xy 1.778 -1.8796) (xy 1.778 1.8796)
			)
			(stroke
				(width 0)
				(type default)
			)
			(fill no)
			(layer "F.CrtYd")
		)
		(fp_poly
			(pts
				(xy -1.778 1.8796) (xy -1.778 -1.8796) (xy 1.778 -1.8796) (xy 1.778 1.8796)
			)
			(stroke
				(width 0)
				(type default)
			)
			(fill no)
			(layer "F.Fab")
		)
		(pad "D" smd custom
			(at 0 -0.9525 180)
			(size 0.1905 0.1905)
			(layers "F.Cu" "F.Mask" "F.Paste")
			(net "LED_Q_5")
			(options
				(clearance outline)
				(anchor circle)
			)
			(primitives
				(gr_poly
					(pts
						(arc
							(start -0.1778 0.5715)
							(mid -0.321484 0.511984)
							(end -0.381 0.3683)
						)
						(arc
							(start -0.381 -0.3683)
							(mid -0.321484 -0.511984)
							(end -0.1778 -0.5715)
						)
						(arc
							(start 0.1778 -0.5715)
							(mid 0.321484 -0.511984)
							(end 0.381 -0.3683)
						)
						(arc
							(start 0.381 0.3683)
							(mid 0.321484 0.511984)
							(end 0.1778 0.5715)
						)
					)
					(width 0)
					(fill yes)
				)
			)
		)
		(pad "G" smd custom
			(at -0.98425 0.9525 180)
			(size 0.1905 0.1905)
			(layers "F.Cu" "F.Mask" "F.Paste")
			(net "UPLINK5_R")
			(options
				(clearance outline)
				(anchor circle)
			)
			(primitives
				(gr_poly
					(pts
						(arc
							(start -0.1778 0.5715)
							(mid -0.321484 0.511984)
							(end -0.381 0.3683)
						)
						(arc
							(start -0.381 -0.3683)
							(mid -0.321484 -0.511984)
							(end -0.1778 -0.5715)
						)
						(arc
							(start 0.1778 -0.5715)
							(mid 0.321484 -0.511984)
							(end 0.381 -0.3683)
						)
						(arc
							(start 0.381 0.3683)
							(mid 0.321484 0.511984)
							(end 0.1778 0.5715)
						)
					)
					(width 0)
					(fill yes)
				)
			)
		)
		(pad "S" smd custom
			(at 0.98425 0.9525 180)
			(size 0.1905 0.1905)
			(layers "F.Cu" "F.Mask" "F.Paste")
			(net "GND")
			(options
				(clearance outline)
				(anchor circle)
			)
			(primitives
				(gr_poly
					(pts
						(arc
							(start -0.1778 0.5715)
							(mid -0.321484 0.511984)
							(end -0.381 0.3683)
						)
						(arc
							(start -0.381 -0.3683)
							(mid -0.321484 -0.511984)
							(end -0.1778 -0.5715)
						)
						(arc
							(start 0.1778 -0.5715)
							(mid 0.321484 -0.511984)
							(end 0.381 -0.3683)
						)
						(arc
							(start 0.381 0.3683)
							(mid 0.321484 0.511984)
							(end 0.1778 0.5715)
						)
					)
					(width 0)
					(fill yes)
				)
			)
		)
	)
	(footprint ""
		(layer "F.Cu")
		(at 229.108 -86.7664 90)
		(property "Reference" "R591"
			(at 0 0 90)
			(layer "F.SilkS")
			(hide yes)
			(effects
				(font
					(size 1.27 1.27)
				)
			)
		)
		(property "Value" "4K7R2F-GP"
			(at 0.064008 -3.993896 90)
			(unlocked yes)
			(layer "F.Fab")
			(hide yes)
			(effects
				(font
					(size 1.016 1.016)
					(thickness 0.1524)
				)
			)
		)
		(property "Device Type" "R402H16"
			(at 0.064008 -5.517896 90)
			(unlocked yes)
			(layer "F.Fab")
			(hide yes)
			(effects
				(font
					(size 1.016 1.016)
					(thickness 0.1524)
				)
			)
		)
		(duplicate_pad_numbers_are_jumpers no)
		(fp_line
			(start 0.508 -0.9398)
			(end -0.508 -0.9398)
			(stroke
				(width 0.1524)
				(type default)
			)
			(layer "F.SilkS")
		)
		(fp_line
			(start -0.508 -0.9398)
			(end -0.508 0.9398)
			(stroke
				(width 0.1524)
				(type default)
			)
			(layer "F.SilkS")
		)
		(fp_rect
			(start -0.508 0.9398)
			(end 0.508 -0.9398)
			(stroke
				(width 0)
				(type default)
			)
			(fill no)
			(layer "F.CrtYd")
		)
		(fp_rect
			(start -0.508 0.9398)
			(end 0.508 -0.9398)
			(stroke
				(width 0)
				(type default)
			)
			(fill no)
			(layer "F.Fab")
		)
		(pad "1" smd custom
			(at 0 -0.4445 90)
			(size 0.1397 0.1397)
			(layers "F.Cu" "F.Mask" "F.Paste")
			(net "TEMP_3_A2")
			(options
				(clearance outline)
				(anchor circle)
			)
			(primitives
				(gr_poly
					(pts
						(arc
							(start -0.1778 -0.2794)
							(mid -0.249642 -0.249642)
							(end -0.2794 -0.1778)
						)
						(arc
							(start -0.2794 0.1778)
							(mid -0.249642 0.249642)
							(end -0.1778 0.2794)
						)
						(arc
							(start 0.1778 0.2794)
							(mid 0.249642 0.249642)
							(end 0.2794 0.1778)
						)
						(arc
							(start 0.2794 -0.1778)
							(mid 0.249642 -0.249642)
							(end 0.1778 -0.2794)
						)
					)
					(width 0)
					(fill yes)
				)
			)
		)
		(pad "2" smd custom
			(at 0 0.4445 90)
			(size 0.1397 0.1397)
			(layers "F.Cu" "F.Mask" "F.Paste")
			(net "GND")
			(options
				(clearance outline)
				(anchor circle)
			)
			(primitives
				(gr_poly
					(pts
						(arc
							(start -0.1778 -0.2794)
							(mid -0.249642 -0.249642)
							(end -0.2794 -0.1778)
						)
						(arc
							(start -0.2794 0.1778)
							(mid -0.249642 0.249642)
							(end -0.1778 0.2794)
						)
						(arc
							(start 0.1778 0.2794)
							(mid 0.249642 0.249642)
							(end 0.2794 0.1778)
						)
						(arc
							(start 0.2794 -0.1778)
							(mid 0.249642 -0.249642)
							(end 0.1778 -0.2794)
						)
					)
					(width 0)
					(fill yes)
				)
			)
		)
	)
	(footprint ""
		(layer "F.Cu")
		(at 27.488896 -40.992298)
		(property "Reference" "R514"
			(at 0 0 0)
			(layer "F.SilkS")
			(hide yes)
			(effects
				(font
					(size 1.27 1.27)
				)
			)
		)
		(property "Value" "150R3J-L-GP"
			(at -0.0254 -2.5146 0)
			(unlocked yes)
			(layer "F.Fab")
			(hide yes)
			(effects
				(font
					(size 1.016 1.016)
					(thickness 0.1524)
				)
			)
		)
		(property "Device Type" "R603H22"
			(at -0.0254 -4.0386 0)
			(unlocked yes)
			(layer "F.Fab")
			(hide yes)
			(effects
				(font
					(size 1.016 1.016)
					(thickness 0.1524)
				)
			)
		)
		(duplicate_pad_numbers_are_jumpers no)
		(fp_line
			(start -0.4826 0)
			(end -0.2032 0)
			(stroke
				(width 0.2032)
				(type default)
			)
			(layer "F.SilkS")
		)
		(fp_line
			(start 0.2032 0)
			(end 0.4826 0)
			(stroke
				(width 0.2032)
				(type default)
			)
			(layer "F.SilkS")
		)
		(fp_rect
			(start -0.5842 1.3335)
			(end 0.5842 -1.3335)
			(stroke
				(width 0)
				(type default)
			)
			(fill no)
			(layer "F.CrtYd")
		)
		(fp_rect
			(start -0.5842 1.3335)
			(end 0.5842 -1.3335)
			(stroke
				(width 0)
				(type default)
			)
			(fill no)
			(layer "F.Fab")
		)
		(pad "1" smd custom
			(at 0 -0.762)
			(size 0.2159 0.2159)
			(layers "F.Cu" "F.Mask" "F.Paste")
			(net "P3V3_STBY")
			(options
				(clearance outline)
				(anchor circle)
			)
			(primitives
				(gr_poly
					(pts
						(arc
							(start -0.3302 -0.4318)
							(mid -0.402042 -0.402042)
							(end -0.4318 -0.3302)
						)
						(arc
							(start -0.4318 0.3302)
							(mid -0.402042 0.402042)
							(end -0.3302 0.4318)
						)
						(arc
							(start 0.3302 0.4318)
							(mid 0.402042 0.402042)
							(end 0.4318 0.3302)
						)
						(arc
							(start 0.4318 -0.3302)
							(mid 0.402042 -0.402042)
							(end 0.3302 -0.4318)
						)
					)
					(width 0)
					(fill yes)
				)
			)
		)
		(pad "2" smd custom
			(at 0 0.762)
			(size 0.2159 0.2159)
			(layers "F.Cu" "F.Mask" "F.Paste")
			(net "LED_MDI0_100M_1G_N")
			(options
				(clearance outline)
				(anchor circle)
			)
			(primitives
				(gr_poly
					(pts
						(arc
							(start -0.3302 -0.4318)
							(mid -0.402042 -0.402042)
							(end -0.4318 -0.3302)
						)
						(arc
							(start -0.4318 0.3302)
							(mid -0.402042 0.402042)
							(end -0.3302 0.4318)
						)
						(arc
							(start 0.3302 0.4318)
							(mid 0.402042 0.402042)
							(end 0.4318 0.3302)
						)
						(arc
							(start 0.4318 -0.3302)
							(mid 0.402042 -0.402042)
							(end 0.3302 -0.4318)
						)
					)
					(width 0)
					(fill yes)
				)
			)
		)
	)
	(footprint ""
		(layer "F.Cu")
		(at 340.233 -48.895 -90)
		(property "Reference" "PC215"
			(at 0 0 270)
			(layer "F.SilkS")
			(hide yes)
			(effects
				(font
					(size 1.27 1.27)
				)
			)
		)
		(property "Value" "SC22U25V6KX-GP-U"
			(at -2.860802 -5.279644 270)
			(unlocked yes)
			(layer "F.Fab")
			(hide yes)
			(effects
				(font
					(size 1.016 1.016)
					(thickness 0.1524)
				)
			)
		)
		(property "Device Type" "C1206-TO0D3H75"
			(at -2.860802 -6.803644 270)
			(unlocked yes)
			(layer "F.Fab")
			(hide yes)
			(effects
				(font
					(size 1.016 1.016)
					(thickness 0.1524)
				)
			)
		)
		(duplicate_pad_numbers_are_jumpers no)
		(fp_line
			(start -1.3081 2.3749)
			(end -1.3081 -2.3749)
			(stroke
				(width 0.1524)
				(type default)
			)
			(layer "F.SilkS")
		)
		(fp_line
			(start 1.3081 2.3749)
			(end -1.3081 2.3749)
			(stroke
				(width 0.1524)
				(type default)
			)
			(layer "F.SilkS")
		)
		(fp_line
			(start -1.3081 -2.3749)
			(end 1.3081 -2.3749)
			(stroke
				(width 0.1524)
				(type default)
			)
			(layer "F.SilkS")
		)
		(fp_line
			(start 1.3081 -2.3749)
			(end 1.3081 2.3749)
			(stroke
				(width 0.1524)
				(type default)
			)
			(layer "F.SilkS")
		)
		(fp_rect
			(start -0.8001 1.6002)
			(end 0.8001 -1.6002)
			(stroke
				(width 0)
				(type default)
			)
			(fill no)
			(layer "F.CrtYd")
		)
		(fp_poly
			(pts
				(xy -1.5621 2.4511) (xy -1.5621 1.6002) (xy 0.8001 1.6002) (xy 0.8001 -1.6002) (xy -0.8001 -1.6002)
				(xy -0.8001 1.5875) (xy -1.5621 1.5875) (xy -1.5621 -2.4511) (xy 1.5621 -2.4511) (xy 1.5621 2.4511)
			)
			(stroke
				(width 0)
				(type default)
			)
			(fill no)
			(layer "F.CrtYd")
		)
		(fp_rect
			(start -1.5621 2.4511)
			(end 1.5621 -2.4511)
			(stroke
				(width 0)
				(type default)
			)
			(fill no)
			(layer "F.Fab")
		)
		(pad "1" smd rect
			(at 0 -1.392936 270)
			(size 2.1082 1.4478)
			(layers "F.Cu" "F.Mask" "F.Paste")
			(net "P0V9_E_VIN")
		)
		(pad "2" smd rect
			(at 0 1.392936 270)
			(size 2.1082 1.4478)
			(layers "F.Cu" "F.Mask" "F.Paste")
			(net "GND")
		)
	)
	(footprint ""
		(layer "F.Cu")
		(at 45.933106 -114.489738 90)
		(property "Reference" "R546"
			(at 0 0 90)
			(layer "F.SilkS")
			(hide yes)
			(effects
				(font
					(size 1.27 1.27)
				)
			)
		)
		(property "Value" "10KR2F-2-GP"
			(at 0.064008 -3.993896 90)
			(unlocked yes)
			(layer "F.Fab")
			(hide yes)
			(effects
				(font
					(size 1.016 1.016)
					(thickness 0.1524)
				)
			)
		)
		(property "Device Type" "R402H16"
			(at 0.064008 -5.517896 90)
			(unlocked yes)
			(layer "F.Fab")
			(hide yes)
			(effects
				(font
					(size 1.016 1.016)
					(thickness 0.1524)
				)
			)
		)
		(duplicate_pad_numbers_are_jumpers no)
		(fp_line
			(start 0.508 -0.9398)
			(end -0.508 -0.9398)
			(stroke
				(width 0.1524)
				(type default)
			)
			(layer "F.SilkS")
		)
		(fp_line
			(start -0.508 -0.9398)
			(end -0.508 0.9398)
			(stroke
				(width 0.1524)
				(type default)
			)
			(layer "F.SilkS")
		)
		(fp_rect
			(start -0.508 0.9398)
			(end 0.508 -0.9398)
			(stroke
				(width 0)
				(type default)
			)
			(fill no)
			(layer "F.CrtYd")
		)
		(fp_rect
			(start -0.508 0.9398)
			(end 0.508 -0.9398)
			(stroke
				(width 0)
				(type default)
			)
			(fill no)
			(layer "F.Fab")
		)
		(pad "1" smd custom
			(at 0 -0.4445 90)
			(size 0.1397 0.1397)
			(layers "F.Cu" "F.Mask" "F.Paste")
			(net "P3V3_STBY")
			(options
				(clearance outline)
				(anchor circle)
			)
			(primitives
				(gr_poly
					(pts
						(arc
							(start -0.1778 -0.2794)
							(mid -0.249642 -0.249642)
							(end -0.2794 -0.1778)
						)
						(arc
							(start -0.2794 0.1778)
							(mid -0.249642 0.249642)
							(end -0.1778 0.2794)
						)
						(arc
							(start 0.1778 0.2794)
							(mid 0.249642 0.249642)
							(end 0.2794 0.1778)
						)
						(arc
							(start 0.2794 -0.1778)
							(mid 0.249642 -0.249642)
							(end 0.1778 -0.2794)
						)
					)
					(width 0)
					(fill yes)
				)
			)
		)
		(pad "2" smd custom
			(at 0 0.4445 90)
			(size 0.1397 0.1397)
			(layers "F.Cu" "F.Mask" "F.Paste")
			(net "BMC_JTAG_L_EN")
			(options
				(clearance outline)
				(anchor circle)
			)
			(primitives
				(gr_poly
					(pts
						(arc
							(start -0.1778 -0.2794)
							(mid -0.249642 -0.249642)
							(end -0.2794 -0.1778)
						)
						(arc
							(start -0.2794 0.1778)
							(mid -0.249642 0.249642)
							(end -0.1778 0.2794)
						)
						(arc
							(start 0.1778 0.2794)
							(mid 0.249642 0.249642)
							(end 0.2794 0.1778)
						)
						(arc
							(start 0.2794 -0.1778)
							(mid 0.249642 -0.249642)
							(end 0.1778 -0.2794)
						)
					)
					(width 0)
					(fill yes)
				)
			)
		)
	)
	(footprint ""
		(layer "F.Cu")
		(at 54.102 -149.987 90)
		(property "Reference" "U134"
			(at 0 0 90)
			(layer "F.SilkS")
			(hide yes)
			(effects
				(font
					(size 1.27 1.27)
				)
			)
		)
		(property "Value" "TMP75AIDGKR-GP"
			(at -0.1143 -9.1948 90)
			(unlocked yes)
			(layer "F.Fab")
			(hide yes)
			(effects
				(font
					(size 1.016 1.016)
					(thickness 0.1524)
				)
			)
		)
		(property "Device Type" "MSOP8-1H44"
			(at -0.1143 -10.795 90)
			(unlocked yes)
			(layer "F.Fab")
			(hide yes)
			(effects
				(font
					(size 1.016 1.016)
					(thickness 0.1524)
				)
			)
		)
		(duplicate_pad_numbers_are_jumpers no)
		(fp_line
			(start 1.0795 -1.016)
			(end -1.9558 -1.016)
			(stroke
				(width 0.1524)
				(type default)
			)
			(layer "F.SilkS")
		)
		(fp_line
			(start -1.9558 -1.016)
			(end -1.9558 1.016)
			(stroke
				(width 0.1524)
				(type default)
			)
			(layer "F.SilkS")
		)
		(fp_line
			(start -1.9558 -0.5461)
			(end -1.4478 -0.0381)
			(stroke
				(width 0.1524)
				(type default)
			)
			(layer "F.SilkS")
		)
		(fp_line
			(start -1.4478 -0.0381)
			(end -1.9558 0.4699)
			(stroke
				(width 0.1524)
				(type default)
			)
			(layer "F.SilkS")
		)
		(fp_line
			(start 1.0795 1.016)
			(end 1.0795 -1.016)
			(stroke
				(width 0.1524)
				(type default)
			)
			(layer "F.SilkS")
		)
		(fp_line
			(start -1.9558 1.016)
			(end 1.0795 1.016)
			(stroke
				(width 0.1524)
				(type default)
			)
			(layer "F.SilkS")
		)
		(fp_line
			(start -1.778 1.0922)
			(end -1.778 3.048)
			(stroke
				(width 0.508)
				(type default)
			)
			(layer "F.SilkS")
		)
		(fp_poly
			(pts
				(xy -1.1557 -1.016) (xy -1.1557 1.016) (xy 1.1557 1.016) (xy 1.1557 -1.016)
			)
			(stroke
				(width 0)
				(type default)
			)
			(fill yes)
			(layer "F.SilkS")
		)
		(fp_rect
			(start -1.4986 2.4511)
			(end 1.4986 -2.4511)
			(stroke
				(width 0)
				(type default)
			)
			(fill no)
			(layer "F.CrtYd")
		)
		(fp_poly
			(pts
				(xy -2.032 3.302) (xy -2.032 -3.302) (xy 2.032 -3.302) (xy 2.032 -2.1209) (xy 1.4986 -2.1209) (xy 1.4986 -2.4511)
				(xy -1.4986 -2.4511) (xy -1.4986 2.4511) (xy 1.4986 2.4511) (xy 1.4986 -2.1082) (xy 2.032 -2.1082)
				(xy 2.032 3.302)
			)
			(stroke
				(width 0)
				(type default)
			)
			(fill no)
			(layer "F.CrtYd")
		)
		(fp_rect
			(start -2.032 3.302)
			(end 2.032 -3.302)
			(stroke
				(width 0)
				(type default)
			)
			(fill no)
			(layer "F.Fab")
		)
		(pad "1" smd rect
			(at -0.97536 2.05486 90)
			(size 0.3556 1.524)
			(layers "F.Cu" "F.Mask" "F.Paste")
			(net "TEMP_2_SDA")
		)
		(pad "2" smd rect
			(at -0.32512 2.05486 90)
			(size 0.3556 1.524)
			(layers "F.Cu" "F.Mask" "F.Paste")
			(net "TEMP_2_SCL")
		)
		(pad "3" smd rect
			(at 0.32512 2.05486 90)
			(size 0.3556 1.524)
			(layers "F.Cu" "F.Mask" "F.Paste")
			(net "TEMP_2_ALERT")
		)
		(pad "4" smd rect
			(at 0.97536 2.05486 90)
			(size 0.3556 1.524)
			(layers "F.Cu" "F.Mask" "F.Paste")
			(net "GND")
		)
		(pad "5" smd rect
			(at 0.97536 -2.05486 90)
			(size 0.3556 1.524)
			(layers "F.Cu" "F.Mask" "F.Paste")
			(net "TEMP_2_A2")
		)
		(pad "6" smd rect
			(at 0.32512 -2.05486 90)
			(size 0.3556 1.524)
			(layers "F.Cu" "F.Mask" "F.Paste")
			(net "TEMP_2_A1")
		)
		(pad "7" smd rect
			(at -0.32512 -2.05486 90)
			(size 0.3556 1.524)
			(layers "F.Cu" "F.Mask" "F.Paste")
			(net "TEMP_2_A0")
		)
		(pad "8" smd rect
			(at -0.97536 -2.05486 90)
			(size 0.3556 1.524)
			(layers "F.Cu" "F.Mask" "F.Paste")
			(net "P3V3_STBY")
		)
	)
	(footprint ""
		(layer "F.Cu")
		(at 310.007 -59.4106)
		(property "Reference" "PG48"
			(at 0 0 0)
			(layer "F.SilkS")
			(hide yes)
			(effects
				(font
					(size 1.27 1.27)
				)
			)
		)
		(property "Value" "GAP-CLOSE-PWR-3-GP"
			(at 0.0254 -6.5786 0)
			(unlocked yes)
			(layer "F.Fab")
			(hide yes)
			(effects
				(font
					(size 1.016 1.016)
					(thickness 0.1524)
				)
			)
		)
		(property "Device Type" "GAP-CLOSE-PWR-3"
			(at 0.0254 -8.255 0)
			(unlocked yes)
			(layer "F.Fab")
			(hide yes)
			(effects
				(font
					(size 1.016 1.016)
					(thickness 0.1524)
				)
			)
		)
		(duplicate_pad_numbers_are_jumpers no)
		(fp_rect
			(start -0.7112 0.4572)
			(end 0.7112 -0.4572)
			(stroke
				(width 0)
				(type default)
			)
			(fill no)
			(layer "F.CrtYd")
		)
		(fp_poly
			(pts
				(xy -0.7112 -0.4572) (xy 0.7112 -0.4572) (xy 0.7112 0.4572) (xy -0.7112 0.4572)
			)
			(stroke
				(width 0)
				(type default)
			)
			(fill no)
			(layer "F.Fab")
		)
		(pad "1" smd rect
			(at -0.3048 0)
			(size 0.6604 0.762)
			(layers "F.Cu" "F.Mask" "F.Paste")
			(net "DUT_VDD")
		)
		(pad "2" smd rect
			(at 0.3048 0)
			(size 0.6604 0.762)
			(layers "F.Cu" "F.Mask" "F.Paste")
			(net "P0V9_E")
		)
	)
)
